(kicad_pcb
	(version 20221018)
	(generator pcbnew)
	(general
    (thickness 1.518)
  )
	(paper "A4")
	(title_block
    (title "Kria K26 Devboard")
    (date "2024-03-26")
    (rev "1.2.5")
    (comment 1 "www.antmicro.com")
    (comment 2 "Antmicro Ltd.")
		(comment 9 "footprint 368 of 660 (U17), pads 1-81 of 101")
	)
	(layers
    (0 "F.Cu" mixed)
    (1 "In1.Cu" power)
    (2 "In2.Cu" mixed)
    (3 "In3.Cu" power)
    (4 "In4.Cu" mixed)
    (5 "In5.Cu" power)
    (6 "In6.Cu" mixed)
    (31 "B.Cu" power)
    (32 "B.Adhes" user "B.Adhesive")
    (33 "F.Adhes" user "F.Adhesive")
    (34 "B.Paste" user)
    (35 "F.Paste" user)
    (36 "B.SilkS" user "B.Silkscreen")
    (37 "F.SilkS" user "F.Silkscreen")
    (38 "B.Mask" user)
    (39 "F.Mask" user)
    (40 "Dwgs.User" user "User.Drawings")
    (41 "Cmts.User" user "User.Comments")
    (42 "Eco1.User" user "User.Eco1")
    (43 "Eco2.User" user "User.Eco2")
    (44 "Edge.Cuts" user)
    (45 "Margin" user)
    (46 "B.CrtYd" user "B.Courtyard")
    (47 "F.CrtYd" user "F.Courtyard")
    (48 "B.Fab" user)
    (49 "F.Fab" user)
  )
	(footprint "kria-k26-devboard-footprints:VQFN-100-1EP_12x12x0.85mm_P0.4mm"
    (layer "F.Cu")
    (at 122.118942 84.534861 180)
    (property "Author" "Antmicro")
    (property "License" "Apache-2.0")
    (property "MPN" "USB7016/KDX")
    (property "Manufacturer" "Microchip Technology")
    (property "Sheetfile" "usb.kicad_sch")
    (property "Sheetname" "USB")
    (property "ki_description" "USB hub controller")
    (property "ki_keywords" "SMT, INTERFACE, CONTROLLER, IC, USB, HUB")
    (attr smd)
    (fp_text reference "U17" (at 6.678942 4.194861 270) (layer "F.SilkS")
        (effects (font (size 0.7 0.7) (thickness 0.15)) (justify left bottom))
    )
    (fp_text value "USB7016_KDX" (at 0 7.6 180) (layer "F.Fab")
        (effects (font (size 0.7 0.7) (thickness 0.15)) (justify left bottom))
    )
    (pad "1" smd roundrect (at -5.789 -4.802 270) (size 0.204 1.011199) (layers "F.Cu" "F.Paste" "F.Mask") (roundrect_rratio 0.25)
      (net 175 "/Reset logic/~{USB_HUB_RESET}") (pinfunction "RESET_N") (pintype "input"))
    (pad "2" smd roundrect (at -5.789 -4.401 270) (size 0.204 1.011199) (layers "F.Cu" "F.Paste" "F.Mask") (roundrect_rratio 0.25)
      (net 663 "Net-(U17-PF30)") (pinfunction "PF30") (pintype "bidirectional"))
    (pad "3" smd roundrect (at -5.789 -4 270) (size 0.204 1.011199) (layers "F.Cu" "F.Paste" "F.Mask") (roundrect_rratio 0.25)
      (net 664 "Net-(U17-PF31)") (pinfunction "PF31") (pintype "bidirectional"))
    (pad "4" smd roundrect (at -5.789 -3.601 270) (size 0.204 1.011199) (layers "F.Cu" "F.Paste" "F.Mask") (roundrect_rratio 0.25)
      (net 697 "Net-(U17-DP1_VBUS_MON)") (pinfunction "DP1_VBUS_MON") (pintype "bidirectional"))
    (pad "5" smd roundrect (at -5.789 -3.201 270) (size 0.204 1.011199) (layers "F.Cu" "F.Paste" "F.Mask") (roundrect_rratio 0.25)
      (net 68 "/USB/USB1_P") (pinfunction "USB2DN_DP1/PRT_DIS_P1") (pintype "bidirectional"))
    (pad "6" smd roundrect (at -5.789 -2.801 270) (size 0.204 1.011199) (layers "F.Cu" "F.Paste" "F.Mask") (roundrect_rratio 0.25)
      (net 67 "/USB/USB1_N") (pinfunction "USB2DN_DM1/PRT_DIS_M1") (pintype "bidirectional"))
    (pad "7" smd roundrect (at -5.789 -2.4 270) (size 0.204 1.011199) (layers "F.Cu" "F.Paste" "F.Mask") (roundrect_rratio 0.25)
      (net 61 "/USB/USB1_TX_P") (pinfunction "USB3DN_TXDP1A") (pintype "bidirectional"))
    (pad "8" smd roundrect (at -5.789 -2.001 270) (size 0.204 1.011199) (layers "F.Cu" "F.Paste" "F.Mask") (roundrect_rratio 0.25)
      (net 60 "/USB/USB1_TX_N") (pinfunction "USB3DN_TXDM1A") (pintype "bidirectional"))
    (pad "9" smd roundrect (at -5.789 -1.601 270) (size 0.204 1.011199) (layers "F.Cu" "F.Paste" "F.Mask") (roundrect_rratio 0.25)
      (net 18 "PS_1V2") (pinfunction "VCORE") (pintype "passive"))
    (pad "10" smd roundrect (at -5.789 -1.2 270) (size 0.204 1.011199) (layers "F.Cu" "F.Paste" "F.Mask") (roundrect_rratio 0.25)
      (net 84 "/USB/USB1_RX_P") (pinfunction "USB3DN_RXDP1A") (pintype "bidirectional"))
    (pad "11" smd roundrect (at -5.789 -0.802 270) (size 0.204 1.011199) (layers "F.Cu" "F.Paste" "F.Mask") (roundrect_rratio 0.25)
      (net 83 "/USB/USB1_RX_N") (pinfunction "USB3DN_RXDM1A") (pintype "bidirectional"))
    (pad "12" smd roundrect (at -5.789 -0.401 270) (size 0.204 1.011199) (layers "F.Cu" "F.Paste" "F.Mask") (roundrect_rratio 0.25)
      (net 665 "Net-(U17-DP1_CC1)") (pinfunction "DP1_CC1") (pintype "bidirectional"))
    (pad "13" smd roundrect (at -5.789 0 270) (size 0.204 1.011199) (layers "F.Cu" "F.Paste" "F.Mask") (roundrect_rratio 0.25)
      (net 696 "Net-(U17-DP1_CC2)") (pinfunction "DP1_CC2") (pintype "bidirectional"))
    (pad "14" smd roundrect (at -5.789 0.399 270) (size 0.204 1.011199) (layers "F.Cu" "F.Paste" "F.Mask") (roundrect_rratio 0.25)
      (net 361 "/PCIE M2 key E /M2_USB_P") (pinfunction "USB2DN_DP5/PRT_DIS_P5") (pintype "bidirectional"))
    (pad "15" smd roundrect (at -5.789 0.8 270) (size 0.204 1.011199) (layers "F.Cu" "F.Paste" "F.Mask") (roundrect_rratio 0.25)
      (net 360 "/PCIE M2 key E /M2_USB_N") (pinfunction "USB2DN_DM5/PRT_DIS_M5") (pintype "bidirectional"))
    (pad "16" smd roundrect (at -5.789 1.199 270) (size 0.204 1.011199) (layers "F.Cu" "F.Paste" "F.Mask") (roundrect_rratio 0.25)
      (net 710 "unconnected-(U17-USB3DN_TXDP1B-Pad16)") (pinfunction "USB3DN_TXDP1B") (pintype "bidirectional+no_connect"))
    (pad "17" smd roundrect (at -5.789 1.598 270) (size 0.204 1.011199) (layers "F.Cu" "F.Paste" "F.Mask") (roundrect_rratio 0.25)
      (net 711 "unconnected-(U17-USB3DN_TXDM1B-Pad17)") (pinfunction "USB3DN_TXDM1B") (pintype "bidirectional+no_connect"))
    (pad "18" smd roundrect (at -5.789 1.999 270) (size 0.204 1.011199) (layers "F.Cu" "F.Paste" "F.Mask") (roundrect_rratio 0.25)
      (net 18 "PS_1V2") (pinfunction "VCORE") (pintype "power_in"))
    (pad "19" smd roundrect (at -5.789 2.398 270) (size 0.204 1.011199) (layers "F.Cu" "F.Paste" "F.Mask") (roundrect_rratio 0.25)
      (net 712 "unconnected-(U17-USB3DN_RXDP1B-Pad19)") (pinfunction "USB3DN_RXDP1B") (pintype "bidirectional+no_connect"))
    (pad "20" smd roundrect (at -5.789 2.798 270) (size 0.204 1.011199) (layers "F.Cu" "F.Paste" "F.Mask") (roundrect_rratio 0.25)
      (net 713 "unconnected-(U17-USB3DN_RXDM1B-Pad20)") (pinfunction "USB3DN_RXDM1B") (pintype "bidirectional+no_connect"))
    (pad "21" smd roundrect (at -5.789 3.199 270) (size 0.204 1.011199) (layers "F.Cu" "F.Paste" "F.Mask") (roundrect_rratio 0.25)
      (net 652 "Net-(U17-CFG_STRAP1)") (pinfunction "CFG_STRAP1") (pintype "input"))
    (pad "22" smd roundrect (at -5.789 3.6 270) (size 0.204 1.011199) (layers "F.Cu" "F.Paste" "F.Mask") (roundrect_rratio 0.25)
      (net 653 "Net-(U17-CFG_STRAP2)") (pinfunction "CFG_STRAP2") (pintype "input"))
    (pad "23" smd roundrect (at -5.789 3.999 270) (size 0.204 1.011199) (layers "F.Cu" "F.Paste" "F.Mask") (roundrect_rratio 0.25)
      (net 654 "Net-(U17-CFG_STRAP3)") (pinfunction "CFG_STRAP3") (pintype "input"))
    (pad "24" smd roundrect (at -5.789 4.398 270) (size 0.204 1.011199) (layers "F.Cu" "F.Paste" "F.Mask") (roundrect_rratio 0.25)
      (net 1 "GND") (pinfunction "TESTEN") (pintype "bidirectional"))
    (pad "25" smd roundrect (at -5.789 4.799 270) (size 0.204 1.011199) (layers "F.Cu" "F.Paste" "F.Mask") (roundrect_rratio 0.25)
      (net 18 "PS_1V2") (pinfunction "VCORE") (pintype "passive"))
    (pad "26" smd roundrect (at -4.802 5.788 180) (size 0.204 1.011199) (layers "F.Cu" "F.Paste" "F.Mask") (roundrect_rratio 0.25)
      (net 15 "PS_3V3") (pinfunction "VDD33") (pintype "power_in"))
    (pad "27" smd roundrect (at -4.401 5.788 180) (size 0.204 1.011199) (layers "F.Cu" "F.Paste" "F.Mask") (roundrect_rratio 0.25)
      (net 70 "/USB/USB2_P") (pinfunction "USB2DN_DP2/PRT_DIS_P2") (pintype "bidirectional"))
    (pad "28" smd roundrect (at -4 5.788 180) (size 0.204 1.011199) (layers "F.Cu" "F.Paste" "F.Mask") (roundrect_rratio 0.25)
      (net 69 "/USB/USB2_N") (pinfunction "USB2DN_DM2/PRT_DIS_M2") (pintype "bidirectional"))
    (pad "29" smd roundrect (at -3.601 5.788 180) (size 0.204 1.011199) (layers "F.Cu" "F.Paste" "F.Mask") (roundrect_rratio 0.25)
      (net 63 "/USB/USB2_TX_P") (pinfunction "USB3DN_TXDP2") (pintype "bidirectional"))
    (pad "30" smd roundrect (at -3.201 5.788 180) (size 0.204 1.011199) (layers "F.Cu" "F.Paste" "F.Mask") (roundrect_rratio 0.25)
      (net 62 "/USB/USB2_TX_N") (pinfunction "USB3DN_TXDM2") (pintype "bidirectional"))
    (pad "31" smd roundrect (at -2.801 5.788 180) (size 0.204 1.011199) (layers "F.Cu" "F.Paste" "F.Mask") (roundrect_rratio 0.25)
      (net 18 "PS_1V2") (pinfunction "VCORE") (pintype "passive"))
    (pad "32" smd roundrect (at -2.4 5.788 180) (size 0.204 1.011199) (layers "F.Cu" "F.Paste" "F.Mask") (roundrect_rratio 0.25)
      (net 82 "/USB/USB2_RX_P") (pinfunction "USB3DN_RXDP2") (pintype "bidirectional"))
    (pad "33" smd roundrect (at -2.001 5.788 180) (size 0.204 1.011199) (layers "F.Cu" "F.Paste" "F.Mask") (roundrect_rratio 0.25)
      (net 81 "/USB/USB2_RX_N") (pinfunction "USB3DN_RXDM2") (pintype "bidirectional"))
    (pad "34" smd roundrect (at -1.601 5.788 180) (size 0.204 1.011199) (layers "F.Cu" "F.Paste" "F.Mask") (roundrect_rratio 0.25)
      (net 72 "/USB/USB3_P") (pinfunction "USB2DN_DP3/PRT_DIS_P3") (pintype "bidirectional"))
    (pad "35" smd roundrect (at -1.2 5.788 180) (size 0.204 1.011199) (layers "F.Cu" "F.Paste" "F.Mask") (roundrect_rratio 0.25)
      (net 71 "/USB/USB3_N") (pinfunction "USB2DN_DM3/PRT_DIS_M3") (pintype "bidirectional"))
    (pad "36" smd roundrect (at -0.802 5.788 180) (size 0.204 1.011199) (layers "F.Cu" "F.Paste" "F.Mask") (roundrect_rratio 0.25)
      (net 66 "/USB/USB3_TX_P") (pinfunction "USB3DN_TXDP3") (pintype "bidirectional"))
    (pad "37" smd roundrect (at -0.401 5.788 180) (size 0.204 1.011199) (layers "F.Cu" "F.Paste" "F.Mask") (roundrect_rratio 0.25)
      (net 65 "/USB/USB3_TX_N") (pinfunction "USB3DN_TXDM3") (pintype "bidirectional"))
    (pad "38" smd roundrect (at 0 5.788 180) (size 0.204 1.011199) (layers "F.Cu" "F.Paste" "F.Mask") (roundrect_rratio 0.25)
      (net 18 "PS_1V2") (pinfunction "VCORE") (pintype "passive"))
    (pad "39" smd roundrect (at 0.399 5.788 180) (size 0.204 1.011199) (layers "F.Cu" "F.Paste" "F.Mask") (roundrect_rratio 0.25)
      (net 80 "/USB/USB3_RX_P") (pinfunction "USB3DN_RXDP3") (pintype "bidirectional"))
    (pad "40" smd roundrect (at 0.8 5.788 180) (size 0.204 1.011199) (layers "F.Cu" "F.Paste" "F.Mask") (roundrect_rratio 0.25)
      (net 79 "/USB/USB3_RX_N") (pinfunction "USB3DN_RXDM3") (pintype "bidirectional"))
    (pad "41" smd roundrect (at 1.199 5.788 180) (size 0.204 1.011199) (layers "F.Cu" "F.Paste" "F.Mask") (roundrect_rratio 0.25)
      (net 15 "PS_3V3") (pinfunction "USB2DN_DM6/PRT_DIS_M6") (pintype "bidirectional"))
    (pad "42" smd roundrect (at 1.598 5.788 180) (size 0.204 1.011199) (layers "F.Cu" "F.Paste" "F.Mask") (roundrect_rratio 0.25)
      (net 15 "PS_3V3") (pinfunction "USB2DN_DP6/PRT_DIS_P6") (pintype "bidirectional"))
    (pad "43" smd roundrect (at 1.999 5.788 180) (size 0.204 1.011199) (layers "F.Cu" "F.Paste" "F.Mask") (roundrect_rratio 0.25)
      (net 15 "PS_3V3") (pinfunction "VDD33") (pintype "passive"))
    (pad "44" smd roundrect (at 2.398 5.788 180) (size 0.204 1.011199) (layers "F.Cu" "F.Paste" "F.Mask") (roundrect_rratio 0.25)
      (net 656 "Net-(U17-PF3)") (pinfunction "PF3") (pintype "bidirectional"))
    (pad "45" smd roundrect (at 2.798 5.788 180) (size 0.204 1.011199) (layers "F.Cu" "F.Paste" "F.Mask") (roundrect_rratio 0.25)
      (net 657 "Net-(U17-PF4)") (pinfunction "PF4") (pintype "bidirectional"))
    (pad "46" smd roundrect (at 3.199 5.788 180) (size 0.204 1.011199) (layers "F.Cu" "F.Paste" "F.Mask") (roundrect_rratio 0.25)
      (net 658 "Net-(U17-PF5)") (pinfunction "PF5") (pintype "bidirectional"))
    (pad "47" smd roundrect (at 3.6 5.788 180) (size 0.204 1.011199) (layers "F.Cu" "F.Paste" "F.Mask") (roundrect_rratio 0.25)
      (net 659 "Net-(U17-PF6)") (pinfunction "PF6") (pintype "bidirectional"))
    (pad "48" smd roundrect (at 3.999 5.788 180) (size 0.204 1.011199) (layers "F.Cu" "F.Paste" "F.Mask") (roundrect_rratio 0.25)
      (net 660 "Net-(U17-PF7)") (pinfunction "PF7") (pintype "bidirectional"))
    (pad "49" smd roundrect (at 4.398 5.788 180) (size 0.204 1.011199) (layers "F.Cu" "F.Paste" "F.Mask") (roundrect_rratio 0.25)
      (net 661 "Net-(U17-PF8)") (pinfunction "PF8") (pintype "bidirectional"))
    (pad "50" smd roundrect (at 4.799 5.788 180) (size 0.204 1.011199) (layers "F.Cu" "F.Paste" "F.Mask") (roundrect_rratio 0.25)
      (net 662 "Net-(U17-PF9)") (pinfunction "PF9") (pintype "bidirectional"))
    (pad "51" smd roundrect (at 5.788 4.799 270) (size 0.204 1.011199) (layers "F.Cu" "F.Paste" "F.Mask") (roundrect_rratio 0.25)
      (net 714 "unconnected-(U17-PF10-Pad51)") (pinfunction "PF10") (pintype "bidirectional+no_connect"))
    (pad "52" smd roundrect (at 5.788 4.398 270) (size 0.204 1.011199) (layers "F.Cu" "F.Paste" "F.Mask") (roundrect_rratio 0.25)
      (net 715 "unconnected-(U17-PF11-Pad52)") (pinfunction "PF11") (pintype "bidirectional+no_connect"))
    (pad "53" smd roundrect (at 5.788 3.999 270) (size 0.204 1.011199) (layers "F.Cu" "F.Paste" "F.Mask") (roundrect_rratio 0.25)
      (net 15 "PS_3V3") (pinfunction "VDD33") (pintype "passive"))
    (pad "54" smd roundrect (at 5.788 3.6 270) (size 0.204 1.011199) (layers "F.Cu" "F.Paste" "F.Mask") (roundrect_rratio 0.25)
      (net 716 "unconnected-(U17-PF12-Pad54)") (pinfunction "PF12") (pintype "bidirectional+no_connect"))
    (pad "55" smd roundrect (at 5.788 3.199 270) (size 0.204 1.011199) (layers "F.Cu" "F.Paste" "F.Mask") (roundrect_rratio 0.25)
      (net 18 "PS_1V2") (pinfunction "VCORE") (pintype "passive"))
    (pad "56" smd roundrect (at 5.788 2.798 270) (size 0.204 1.011199) (layers "F.Cu" "F.Paste" "F.Mask") (roundrect_rratio 0.25)
      (net 305 "/USB/USB_PRT_CTL4") (pinfunction "PF13") (pintype "bidirectional"))
    (pad "57" smd roundrect (at 5.788 2.398 270) (size 0.204 1.011199) (layers "F.Cu" "F.Paste" "F.Mask") (roundrect_rratio 0.25)
      (net 304 "/USB/USB_PRT_CTL3") (pinfunction "PF14") (pintype "bidirectional"))
    (pad "58" smd roundrect (at 5.788 1.999 270) (size 0.204 1.011199) (layers "F.Cu" "F.Paste" "F.Mask") (roundrect_rratio 0.25)
      (net 303 "/USB/USB_PRT_CTL2") (pinfunction "PF15") (pintype "bidirectional"))
    (pad "59" smd roundrect (at 5.788 1.598 270) (size 0.204 1.011199) (layers "F.Cu" "F.Paste" "F.Mask") (roundrect_rratio 0.25)
      (net 717 "unconnected-(U17-PF16-Pad59)") (pinfunction "PF16") (pintype "bidirectional+no_connect"))
    (pad "60" smd roundrect (at 5.788 1.199 270) (size 0.204 1.011199) (layers "F.Cu" "F.Paste" "F.Mask") (roundrect_rratio 0.25)
      (net 302 "/USB/USB_PRT_CTL1") (pinfunction "PF17") (pintype "bidirectional"))
    (pad "61" smd roundrect (at 5.788 0.8 270) (size 0.204 1.011199) (layers "F.Cu" "F.Paste" "F.Mask") (roundrect_rratio 0.25)
      (net 718 "unconnected-(U17-PF18-Pad61)") (pinfunction "PF18") (pintype "bidirectional+no_connect"))
    (pad "62" smd roundrect (at 5.788 0.399 270) (size 0.204 1.011199) (layers "F.Cu" "F.Paste" "F.Mask") (roundrect_rratio 0.25)
      (net 15 "PS_3V3") (pinfunction "VDD33") (pintype "passive"))
    (pad "63" smd roundrect (at 5.788 0 270) (size 0.204 1.011199) (layers "F.Cu" "F.Paste" "F.Mask") (roundrect_rratio 0.25)
      (net 649 "Net-(U17-TEST1)") (pinfunction "TEST1") (pintype "passive"))
    (pad "64" smd roundrect (at 5.788 -0.401 270) (size 0.204 1.011199) (layers "F.Cu" "F.Paste" "F.Mask") (roundrect_rratio 0.25)
      (net 650 "Net-(U17-TEST2)") (pinfunction "TEST2") (pintype "passive"))
    (pad "65" smd roundrect (at 5.788 -0.802 270) (size 0.204 1.011199) (layers "F.Cu" "F.Paste" "F.Mask") (roundrect_rratio 0.25)
      (net 651 "Net-(U17-TEST3)") (pinfunction "TEST3") (pintype "passive"))
    (pad "66" smd roundrect (at 5.788 -1.2 270) (size 0.204 1.011199) (layers "F.Cu" "F.Paste" "F.Mask") (roundrect_rratio 0.25)
      (net 719 "unconnected-(U17-PF19-Pad66)") (pinfunction "PF19") (pintype "bidirectional+no_connect"))
    (pad "67" smd roundrect (at 5.788 -1.601 270) (size 0.204 1.011199) (layers "F.Cu" "F.Paste" "F.Mask") (roundrect_rratio 0.25)
      (net 15 "PS_3V3") (pinfunction "VDD33") (pintype "passive"))
    (pad "68" smd roundrect (at 5.788 -2 270) (size 0.204 1.011199) (layers "F.Cu" "F.Paste" "F.Mask") (roundrect_rratio 0.25)
      (net 643 "Net-(U17-SPI_CLK{slash}PF21)") (pinfunction "SPI_CLK/PF21") (pintype "bidirectional"))
    (pad "69" smd roundrect (at 5.788 -2.4 270) (size 0.204 1.011199) (layers "F.Cu" "F.Paste" "F.Mask") (roundrect_rratio 0.25)
      (net 644 "Net-(U17-SPI_CE_N{slash}CFG_NON_REM{slash}PF20)") (pinfunction "SPI_CE_N/CFG_NON_REM/PF20") (pintype "bidirectional"))
    (pad "70" smd roundrect (at 5.788 -2.801 270) (size 0.204 1.011199) (layers "F.Cu" "F.Paste" "F.Mask") (roundrect_rratio 0.25)
      (net 645 "Net-(U17-SPI_D0{slash}CFG_BC_EN{slash}PF22)") (pinfunction "SPI_D0/CFG_BC_EN/PF22") (pintype "bidirectional"))
    (pad "71" smd roundrect (at 5.788 -3.201 270) (size 0.204 1.011199) (layers "F.Cu" "F.Paste" "F.Mask") (roundrect_rratio 0.25)
      (net 646 "Net-(U17-SPI_D1{slash}PF23)") (pinfunction "SPI_D1/PF23") (pintype "bidirectional"))
    (pad "72" smd roundrect (at 5.788 -3.601 270) (size 0.204 1.011199) (layers "F.Cu" "F.Paste" "F.Mask") (roundrect_rratio 0.25)
      (net 647 "Net-(U17-SPI_D2{slash}PF24)") (pinfunction "SPI_D2/PF24") (pintype "bidirectional"))
    (pad "73" smd roundrect (at 5.788 -4 270) (size 0.204 1.011199) (layers "F.Cu" "F.Paste" "F.Mask") (roundrect_rratio 0.25)
      (net 648 "Net-(U17-SPI_D3{slash}PF25)") (pinfunction "SPI_D3/PF25") (pintype "bidirectional"))
    (pad "74" smd roundrect (at 5.788 -4.401 270) (size 0.204 1.011199) (layers "F.Cu" "F.Paste" "F.Mask") (roundrect_rratio 0.25)
      (net 720 "unconnected-(U17-PF29-Pad74)") (pinfunction "PF29") (pintype "bidirectional+no_connect"))
    (pad "75" smd roundrect (at 5.788 -4.8 270) (size 0.204 1.011199) (layers "F.Cu" "F.Paste" "F.Mask") (roundrect_rratio 0.25)
      (net 666 "Net-(U17-PF26)") (pinfunction "PF26") (pintype "bidirectional"))
    (pad "76" smd roundrect (at 4.799 -5.789 180) (size 0.204 1.011199) (layers "F.Cu" "F.Paste" "F.Mask") (roundrect_rratio 0.25)
      (net 667 "Net-(U17-PF27)") (pinfunction "PF27") (pintype "bidirectional"))
    (pad "77" smd roundrect (at 4.398 -5.789 180) (size 0.204 1.011199) (layers "F.Cu" "F.Paste" "F.Mask") (roundrect_rratio 0.25)
      (net 721 "unconnected-(U17-PF28-Pad77)") (pinfunction "PF28") (pintype "bidirectional+no_connect"))
    (pad "78" smd roundrect (at 3.999 -5.789 180) (size 0.204 1.011199) (layers "F.Cu" "F.Paste" "F.Mask") (roundrect_rratio 0.25)
      (net 18 "PS_1V2") (pinfunction "VCORE") (pintype "passive"))
    (pad "79" smd roundrect (at 3.6 -5.789 180) (size 0.204 1.011199) (layers "F.Cu" "F.Paste" "F.Mask") (roundrect_rratio 0.25)
      (net 15 "PS_3V3") (pinfunction "VDD33") (pintype "passive"))
    (pad "80" smd roundrect (at 3.199 -5.789 180) (size 0.204 1.011199) (layers "F.Cu" "F.Paste" "F.Mask") (roundrect_rratio 0.25)
      (net 275 "/USB/VBUS") (pinfunction "VBUS_MON_UP") (pintype "bidirectional"))
    (pad "81" smd roundrect (at 2.798 -5.789 180) (size 0.204 1.011199) (layers "F.Cu" "F.Paste" "F.Mask") (roundrect_rratio 0.25)
      (net 78 "/USB/USB4_P") (pinfunction "USB2DN_DP4/PRT_DIS_P4") (pintype "bidirectional"))
  )
)
